# T6G (Grand Teton) — schematic netlist excerpt (pin names and nets, part order shuffled) for the footprints in the layout excerpt that follows; sources: Cadence DE-HDL packaged netlist, KiCad conversion of 04192023_DAF0TMB3IC0_F0TG_MB_C_brd_V02_OCP.brd

C1126  Q_CAP  0.1UF 16V 10% X7R  pkg C0402  page 83 : A = P1V8_AUX ; B = GND
C986  Q_CAP  10UF 6.3V 20% X6S  pkg C0402  page 301 : A = P0V9_CPU0_RT2_2A ; B = GND

(kicad_pcb
	(version 20260206)
	(generator "pcbnew")
	(generator_version "10.0")
	(general
		(thickness 1.6)
		(legacy_teardrops no)
	)
	(paper "A4")
	(title_block
		(title "04192023_DAF0TMB3IC0_F0TG_MB_C_brd_V02_OCP.brd")
		(comment 1 "Grand Teton / footprints 8154-8155 of 8354")
	)
	(layers
		(0 "F.Cu" signal "TOP")
		(4 "In1.Cu" signal "GND")
		(6 "In2.Cu" signal "IN1")
		(8 "In3.Cu" signal "GND1")
		(10 "In4.Cu" signal "IN2")
		(12 "In5.Cu" signal "GND2")
		(14 "In6.Cu" signal "IN3")
		(16 "In7.Cu" signal "GND3")
		(18 "In8.Cu" signal "VCC")
		(20 "In9.Cu" signal "VCC1")
		(22 "In10.Cu" signal "GND4")
		(24 "In11.Cu" signal "IN4")
		(26 "In12.Cu" signal "GND5")
		(28 "In13.Cu" signal "IN5")
		(30 "In14.Cu" signal "GND6")
		(32 "In15.Cu" signal "IN6")
		(34 "In16.Cu" signal "GND7")
		(2 "B.Cu" signal "BOTTOM")
		(9 "F.Adhes" user "F.Adhesive")
		(11 "B.Adhes" user "B.Adhesive")
		(13 "F.Paste" user "Package Geometry/Pastemask Top")
		(15 "B.Paste" user "Package Geometry/Pastemask Bottom")
		(5 "F.SilkS" user "Ref Des/Silkscreen Top")
		(7 "B.SilkS" user "Ref Des/Silkscreen Bottom")
		(1 "F.Mask" user "Board Geometry/Soldermask Top")
		(3 "B.Mask" user "Board Geometry/Soldermask Bottom")
		(17 "Dwgs.User" user "User.Drawings")
		(19 "Cmts.User" user "User.Comments")
		(21 "Eco1.User" user "User.Eco1")
		(23 "Eco2.User" user "User.Eco2")
		(25 "Edge.Cuts" user "Board Geometry/Outline")
		(27 "Margin" user)
		(31 "F.CrtYd" user "Package Geometry/Place Bound Top")
		(29 "B.CrtYd" user "Package Geometry/Place Bound Bottom")
		(35 "F.Fab" user "Ref Des/Assembly Top")
		(33 "B.Fab" user "Ref Des/Assembly Bottom")
	)
	(footprint ""
		(layer "B.Cu")
		(at 421.01897 -398.942052 90)
		(property "Reference" "C986"
			(at 0 0 90)
			(layer "B.SilkS")
			(hide yes)
			(effects
				(font
					(size 1.27 1.27)
				)
				(justify mirror)
			)
		)
		(property "Value" ""
			(at 0 0 90)
			(layer "B.Fab")
			(effects
				(font
					(size 1.27 1.27)
				)
				(justify mirror)
			)
		)
		(duplicate_pad_numbers_are_jumpers no)
		(fp_line
			(start 0.7874 -0.4064)
			(end -0.7874 -0.4064)
			(stroke
				(width 0.1524)
				(type default)
			)
			(layer "B.SilkS")
		)
		(fp_line
			(start -0.7874 -0.4064)
			(end -0.7874 0.4064)
			(stroke
				(width 0.1524)
				(type default)
			)
			(layer "B.SilkS")
		)
		(fp_line
			(start 0.7874 0.4064)
			(end 0.7874 -0.4064)
			(stroke
				(width 0.1524)
				(type default)
			)
			(layer "B.SilkS")
		)
		(fp_line
			(start -0.7874 0.4064)
			(end 0.7874 0.4064)
			(stroke
				(width 0.1524)
				(type default)
			)
			(layer "B.SilkS")
		)
		(fp_line
			(start 0.67945 -0.305054)
			(end 0.12065 -0.305054)
			(stroke
				(width 0.1)
				(type default)
			)
			(layer "B.Fab")
		)
		(fp_line
			(start 0.12065 -0.305054)
			(end 0.12065 -0.2794)
			(stroke
				(width 0.1)
				(type default)
			)
			(layer "B.Fab")
		)
		(fp_line
			(start -0.12065 -0.3048)
			(end -0.67945 -0.3048)
			(stroke
				(width 0.1)
				(type default)
			)
			(layer "B.Fab")
		)
		(fp_line
			(start -0.67945 -0.3048)
			(end -0.67945 0.3048)
			(stroke
				(width 0.1)
				(type default)
			)
			(layer "B.Fab")
		)
		(fp_line
			(start 0.12065 -0.2794)
			(end -0.12065 -0.2794)
			(stroke
				(width 0.1)
				(type default)
			)
			(layer "B.Fab")
		)
		(fp_line
			(start -0.12065 -0.2794)
			(end -0.12065 -0.3048)
			(stroke
				(width 0.1)
				(type default)
			)
			(layer "B.Fab")
		)
		(fp_line
			(start 0.12065 0.2794)
			(end 0.12065 0.3048)
			(stroke
				(width 0.1)
				(type default)
			)
			(layer "B.Fab")
		)
		(fp_line
			(start -0.120396 0.2794)
			(end 0.12065 0.2794)
			(stroke
				(width 0.1)
				(type default)
			)
			(layer "B.Fab")
		)
		(fp_line
			(start 0.67945 0.3048)
			(end 0.67945 -0.305054)
			(stroke
				(width 0.1)
				(type default)
			)
			(layer "B.Fab")
		)
		(fp_line
			(start 0.12065 0.3048)
			(end 0.67945 0.3048)
			(stroke
				(width 0.1)
				(type default)
			)
			(layer "B.Fab")
		)
		(fp_line
			(start -0.120396 0.3048)
			(end -0.120396 0.2794)
			(stroke
				(width 0.1)
				(type default)
			)
			(layer "B.Fab")
		)
		(fp_line
			(start -0.67945 0.3048)
			(end -0.120396 0.3048)
			(stroke
				(width 0.1)
				(type default)
			)
			(layer "B.Fab")
		)
		(pad "1" smd circle
			(at 0.40005 0 270)
			(size 0 0)
			(layers "B.Cu" "B.Mask" "B.Paste")
			(net "P0V9_CPU0_RT2_2A")
		)
		(pad "2" smd circle
			(at -0.40005 0 270)
			(size 0 0)
			(layers "B.Cu" "B.Mask" "B.Paste")
			(net "GND")
		)
	)
	(footprint ""
		(layer "B.Cu")
		(at 183.551068 -111.863124 -90)
		(property "Reference" "C1126"
			(at 0 0 90)
			(layer "B.SilkS")
			(hide yes)
			(effects
				(font
					(size 1.27 1.27)
				)
				(justify mirror)
			)
		)
		(property "Value" ""
			(at 0 0 90)
			(layer "B.Fab")
			(effects
				(font
					(size 1.27 1.27)
				)
				(justify mirror)
			)
		)
		(duplicate_pad_numbers_are_jumpers no)
		(fp_line
			(start -0.69215 0.2921)
			(end 0.69215 0.2921)
			(stroke
				(width 0.1524)
				(type default)
			)
			(layer "B.SilkS")
		)
		(fp_line
			(start 0.69215 0.2921)
			(end 0.69215 -0.2921)
			(stroke
				(width 0.1524)
				(type default)
			)
			(layer "B.SilkS")
		)
		(fp_line
			(start -0.69215 -0.2921)
			(end -0.69215 0.2921)
			(stroke
				(width 0.1524)
				(type default)
			)
			(layer "B.SilkS")
		)
		(fp_line
			(start 0.69215 -0.2921)
			(end -0.69215 -0.2921)
			(stroke
				(width 0.1524)
				(type default)
			)
			(layer "B.SilkS")
		)
		(fp_line
			(start -0.51435 0.2794)
			(end 0.51435 0.2794)
			(stroke
				(width 0.1)
				(type default)
			)
			(layer "B.Fab")
		)
		(fp_line
			(start 0.51435 0.2794)
			(end 0.51435 -0.2794)
			(stroke
				(width 0.1)
				(type default)
			)
			(layer "B.Fab")
		)
		(fp_line
			(start -0.51435 -0.2794)
			(end -0.51435 0.2794)
			(stroke
				(width 0.1)
				(type default)
			)
			(layer "B.Fab")
		)
		(fp_line
			(start 0.51435 -0.2794)
			(end -0.51435 -0.2794)
			(stroke
				(width 0.1)
				(type default)
			)
			(layer "B.Fab")
		)
		(pad "1" smd circle
			(at 0.40005 0 90)
			(size 0 0)
			(layers "B.Cu" "B.Mask" "B.Paste")
			(net "P1V8_AUX")
		)
		(pad "2" smd circle
			(at -0.40005 0 90)
			(size 0 0)
			(layers "B.Cu" "B.Mask" "B.Paste")
			(net "GND")
		)
		(zone
			(layer "B.Cu")
			(hatch none 0.5)
			(connect_pads
				(clearance 0)
			)
			(min_thickness 0.25)
			(keepout
				(tracks not_allowed)
				(vias allowed)
				(pads allowed)
				(copperpour not_allowed)
				(footprints allowed)
			)
			(placement
				(enabled no)
				(sheetname "")
			)
			(fill
				(thermal_gap 0.5)
				(thermal_bridge_width 0.5)
				(island_removal_mode 0)
			)
			(polygon
				(pts
					(xy 183.405272 -111.764064) (xy 183.405272 -111.963454) (xy 183.463438 -112.053624) (xy 183.638698 -112.053624)
					(xy 183.697118 -111.963454) (xy 183.697118 -111.764064) (xy 183.638952 -111.672624) (xy 183.463438 -111.672624)
				)
			)
		)
	)
)
